(kicad_pcb
	(version 20260206)
	(generator "pcbnew")
	(generator_version "10.0")
	(general
		(thickness 1.6)
		(legacy_teardrops no)
	)
	(paper "A4")
	(title_block
		(title "netronome-mezz — pcbd0082-001_rev01_jul9_a.brd")
		(comment 1 "Open CloudServer (Microsoft) / footprint 702 of 714 (J4), pads 1-116 of 162")
	)
	(layers
		(0 "F.Cu" signal "TOP")
		(4 "In1.Cu" signal "02_GND")
		(6 "In2.Cu" signal "03_SIG")
		(8 "In3.Cu" signal "04_SIG")
		(10 "In4.Cu" signal "05_GND")
		(12 "In5.Cu" signal "06_PWR1")
		(14 "In6.Cu" signal "07_SIG")
		(16 "In7.Cu" signal "08_SIG")
		(18 "In8.Cu" signal "09_GND")
		(2 "B.Cu" signal "BOTTOM")
		(9 "F.Adhes" user "F.Adhesive")
		(11 "B.Adhes" user "B.Adhesive")
		(13 "F.Paste" user "Package Geometry/Pastemask Top")
		(15 "B.Paste" user "Package Geometry/Pastemask Bottom")
		(5 "F.SilkS" user "Ref Des/Silkscreen Top")
		(7 "B.SilkS" user "Ref Des/Silkscreen Bottom")
		(1 "F.Mask" user "Board Geometry/Soldermask Top")
		(3 "B.Mask" user "Board Geometry/Soldermask Bottom")
		(17 "Dwgs.User" user "User.Drawings")
		(19 "Cmts.User" user "User.Comments")
		(21 "Eco1.User" user "User.Eco1")
		(23 "Eco2.User" user "User.Eco2")
		(25 "Edge.Cuts" user "Board Geometry/Outline")
		(27 "Margin" user)
		(31 "F.CrtYd" user "Package Geometry/Place Bound Top")
		(29 "B.CrtYd" user "Package Geometry/Place Bound Bottom")
		(35 "F.Fab" user "Ref Des/Assembly Top")
		(33 "B.Fab" user "Ref Des/Assembly Bottom")
		(45 "User.4" user "COMPVAL_TYPE_BOTTOM")
	)
	(footprint ""
		(layer "B.Cu")
		(at 12.8524 15.8369 -90)
		(property "Reference" "J4"
			(at -15.81023 -6.1976 0)
			(unlocked yes)
			(layer "B.SilkS")
			(effects
				(font
					(size 0.7874 0.5842)
					(thickness 0.127)
				)
				(justify left mirror)
			)
		)
		(property "Value" "VAL"
			(at -0.181864 1.64592 270)
			(unlocked yes)
			(layer "B.Fab")
			(hide yes)
			(effects
				(font
					(size 1.27 0.9652)
					(thickness 0.1524)
				)
				(justify mirror)
			)
		)
		(property "User Part Number" "PN"
			(at -0.181864 -4.06908 270)
			(unlocked yes)
			(layer "Cmts.User")
			(hide yes)
			(effects
				(font
					(size 1.27 0.9652)
					(thickness 0.1524)
				)
				(justify mirror)
			)
		)
		(property "Device Type" "CONM0071"
			(at -0.181864 -2.16408 270)
			(unlocked yes)
			(layer "B.Fab")
			(hide yes)
			(effects
				(font
					(size 1.27 0.9652)
					(thickness 0.1524)
				)
				(justify mirror)
			)
		)
		(property "Tolerance" "TOL"
			(at -0.181864 3.55092 270)
			(unlocked yes)
			(layer "Cmts.User")
			(hide yes)
			(effects
				(font
					(size 1.27 0.9652)
					(thickness 0.1524)
				)
				(justify mirror)
			)
		)
		(duplicate_pad_numbers_are_jumpers no)
		(pad "" np_thru_hole circle
			(at -14.4907 0 90)
			(size 1.778 1.778)
			(drill 1.27)
			(layers "*.Cu" "*.Mask")
			(padstack
				(mode front_inner_back)
				(layer "Inner"
					(shape circle)
					(size 1.778 1.778)
					(clearance 0.127)
				)
				(layer "B.Cu"
					(shape circle)
					(size 1.778 1.778)
					(thermal_gap 0.127)
				)
			)
		)
		(pad "" np_thru_hole circle
			(at 14.4907 3.048 90)
			(size 1.778 1.778)
			(drill 1.27)
			(layers "*.Cu" "*.Mask")
			(padstack
				(mode front_inner_back)
				(layer "Inner"
					(shape circle)
					(size 1.778 1.778)
					(clearance 0.127)
				)
				(layer "B.Cu"
					(shape circle)
					(size 1.778 1.778)
					(thermal_gap 0.127)
				)
			)
		)
		(pad "1" smd circle
			(at -12.065 -4.445 90)
			(size 0.635 0.635)
			(layers "B.Cu" "B.Mask" "B.Paste")
			(net "GND")
		)
		(pad "2" smd circle
			(at -12.065 -3.175 90)
			(size 0.635 0.635)
			(layers "B.Cu" "B.Mask" "B.Paste")
			(net "PCIE0_RST_L")
		)
		(pad "3" smd circle
			(at -12.065 -1.905 90)
			(size 0.635 0.635)
			(layers "B.Cu" "B.Mask" "B.Paste")
			(net "GND")
		)
		(pad "4" smd circle
			(at -12.065 -0.635 90)
			(size 0.635 0.635)
			(layers "B.Cu" "B.Mask" "B.Paste")
			(net "PCIE0_WAKE_L")
		)
		(pad "5" smd circle
			(at -12.065 0.635 90)
			(size 0.635 0.635)
			(layers "B.Cu" "B.Mask" "B.Paste")
			(net "CPLD_NIC_MEZZ_ID0")
		)
		(pad "6" smd circle
			(at -12.065 1.905 90)
			(size 0.635 0.635)
			(layers "B.Cu" "B.Mask" "B.Paste")
			(net "SMBUS_ALERT_L")
		)
		(pad "7" smd circle
			(at -12.065 3.175 90)
			(size 0.635 0.635)
			(layers "B.Cu" "B.Mask" "B.Paste")
			(net "GND")
		)
		(pad "8" smd circle
			(at -12.065 4.445 90)
			(size 0.635 0.635)
			(layers "B.Cu" "B.Mask" "B.Paste")
			(net "PCIE0_REFCLK_P")
		)
		(pad "9" smd circle
			(at -10.795 -4.445 90)
			(size 0.635 0.635)
			(layers "B.Cu" "B.Mask" "B.Paste")
			(net "NFP_PCIE0_PET0_P")
		)
		(pad "10" smd circle
			(at -10.795 -3.175 90)
			(size 0.635 0.635)
			(layers "B.Cu" "B.Mask" "B.Paste")
			(net "GND")
		)
		(pad "11" smd circle
			(at -10.795 -1.905 90)
			(size 0.635 0.635)
			(layers "B.Cu" "B.Mask" "B.Paste")
			(net "NFP_PCIE0_PER7_P")
		)
		(pad "12" smd circle
			(at -10.795 -0.635 90)
			(size 0.635 0.635)
			(layers "B.Cu" "B.Mask" "B.Paste")
			(net "GND")
		)
		(pad "13" smd circle
			(at -10.795 0.635 90)
			(size 0.635 0.635)
			(layers "B.Cu" "B.Mask" "B.Paste")
			(net "SMBUS_SCL")
		)
		(pad "14" smd circle
			(at -10.795 1.905 90)
			(size 0.635 0.635)
			(layers "B.Cu" "B.Mask" "B.Paste")
			(net "NWK1_MOD_PRES_L")
		)
		(pad "15" smd circle
			(at -10.795 3.175 90)
			(size 0.635 0.635)
			(layers "B.Cu" "B.Mask" "B.Paste")
			(net "GND")
		)
		(pad "16" smd circle
			(at -10.795 4.445 90)
			(size 0.635 0.635)
			(layers "B.Cu" "B.Mask" "B.Paste")
			(net "PCIE0_REFCLK_N")
		)
		(pad "17" smd circle
			(at -9.525 -4.445 90)
			(size 0.635 0.635)
			(layers "B.Cu" "B.Mask" "B.Paste")
			(net "NFP_PCIE0_PET0_N")
		)
		(pad "18" smd circle
			(at -9.525 -3.175 90)
			(size 0.635 0.635)
			(layers "B.Cu" "B.Mask" "B.Paste")
			(net "GND")
		)
		(pad "19" smd circle
			(at -9.525 -1.905 90)
			(size 0.635 0.635)
			(layers "B.Cu" "B.Mask" "B.Paste")
			(net "NFP_PCIE0_PER7_N")
		)
		(pad "20" smd circle
			(at -9.525 -0.635 90)
			(size 0.635 0.635)
			(layers "B.Cu" "B.Mask" "B.Paste")
			(net "GND")
		)
		(pad "21" smd circle
			(at -9.525 0.635 90)
			(size 0.635 0.635)
			(layers "B.Cu" "B.Mask" "B.Paste")
			(net "SMBUS_SDA")
		)
		(pad "22" smd circle
			(at -9.525 1.905 90)
			(size 0.635 0.635)
			(layers "B.Cu" "B.Mask" "B.Paste")
			(net "GND")
		)
		(pad "23" smd circle
			(at -9.525 3.175 90)
			(size 0.635 0.635)
			(layers "B.Cu" "B.Mask" "B.Paste")
			(net "GND")
		)
		(pad "24" smd circle
			(at -9.525 4.445 90)
			(size 0.635 0.635)
			(layers "B.Cu" "B.Mask" "B.Paste")
			(net "GND")
		)
		(pad "25" smd circle
			(at -8.255 -4.445 90)
			(size 0.635 0.635)
			(layers "B.Cu" "B.Mask" "B.Paste")
			(net "GND")
		)
		(pad "26" smd circle
			(at -8.255 -3.175 90)
			(size 0.635 0.635)
			(layers "B.Cu" "B.Mask" "B.Paste")
			(net "NFP_PCIE0_PET1_P")
		)
		(pad "27" smd circle
			(at -8.255 -1.905 90)
			(size 0.635 0.635)
			(layers "B.Cu" "B.Mask" "B.Paste")
			(net "GND")
		)
		(pad "28" smd circle
			(at -8.255 -0.635 90)
			(size 0.635 0.635)
			(layers "B.Cu" "B.Mask" "B.Paste")
			(net "NFP_PCIE0_PER6_P")
		)
		(pad "29" smd circle
			(at -8.255 0.635 90)
			(size 0.635 0.635)
			(layers "B.Cu" "B.Mask" "B.Paste")
			(net "GND")
		)
		(pad "30" smd circle
			(at -8.255 1.905 90)
			(size 0.635 0.635)
			(layers "B.Cu" "B.Mask" "B.Paste")
			(net "_NC_NCSI_TXD_0")
		)
		(pad "31" smd circle
			(at -8.255 3.175 90)
			(size 0.635 0.635)
			(layers "B.Cu" "B.Mask" "B.Paste")
			(net "GND")
		)
		(pad "32" smd circle
			(at -8.255 4.445 90)
			(size 0.635 0.635)
			(layers "B.Cu" "B.Mask" "B.Paste")
			(net "NFP_SERDES1_TX0_P")
		)
		(pad "33" smd circle
			(at -6.985 -4.445 90)
			(size 0.635 0.635)
			(layers "B.Cu" "B.Mask" "B.Paste")
			(net "GND")
		)
		(pad "34" smd circle
			(at -6.985 -3.175 90)
			(size 0.635 0.635)
			(layers "B.Cu" "B.Mask" "B.Paste")
			(net "NFP_PCIE0_PET1_N")
		)
		(pad "35" smd circle
			(at -6.985 -1.905 90)
			(size 0.635 0.635)
			(layers "B.Cu" "B.Mask" "B.Paste")
			(net "GND")
		)
		(pad "36" smd circle
			(at -6.985 -0.635 90)
			(size 0.635 0.635)
			(layers "B.Cu" "B.Mask" "B.Paste")
			(net "NFP_PCIE0_PER6_N")
		)
		(pad "37" smd circle
			(at -6.985 0.635 90)
			(size 0.635 0.635)
			(layers "B.Cu" "B.Mask" "B.Paste")
			(net "GND")
		)
		(pad "38" smd circle
			(at -6.985 1.905 90)
			(size 0.635 0.635)
			(layers "B.Cu" "B.Mask" "B.Paste")
			(net "_NC_NCSI_TXD_1")
		)
		(pad "39" smd circle
			(at -6.985 3.175 90)
			(size 0.635 0.635)
			(layers "B.Cu" "B.Mask" "B.Paste")
			(net "GND")
		)
		(pad "40" smd circle
			(at -6.985 4.445 90)
			(size 0.635 0.635)
			(layers "B.Cu" "B.Mask" "B.Paste")
			(net "NFP_SERDES1_TX0_N")
		)
		(pad "41" smd circle
			(at -5.715 -4.445 90)
			(size 0.635 0.635)
			(layers "B.Cu" "B.Mask" "B.Paste")
			(net "NFP_PCIE0_PET2_P")
		)
		(pad "42" smd circle
			(at -5.715 -3.175 90)
			(size 0.635 0.635)
			(layers "B.Cu" "B.Mask" "B.Paste")
			(net "GND")
		)
		(pad "43" smd circle
			(at -5.715 -1.905 90)
			(size 0.635 0.635)
			(layers "B.Cu" "B.Mask" "B.Paste")
			(net "NFP_PCIE0_PER5_P")
		)
		(pad "44" smd circle
			(at -5.715 -0.635 90)
			(size 0.635 0.635)
			(layers "B.Cu" "B.Mask" "B.Paste")
			(net "GND")
		)
		(pad "45" smd circle
			(at -5.715 0.635 90)
			(size 0.635 0.635)
			(layers "B.Cu" "B.Mask" "B.Paste")
			(net "_NC_NCSI_RXD_0")
		)
		(pad "46" smd circle
			(at -5.715 1.905 90)
			(size 0.635 0.635)
			(layers "B.Cu" "B.Mask" "B.Paste")
			(net "GND")
		)
		(pad "47" smd circle
			(at -5.715 3.175 90)
			(size 0.635 0.635)
			(layers "B.Cu" "B.Mask" "B.Paste")
			(net "NFP_SERDES1_TX1_P")
		)
		(pad "48" smd circle
			(at -5.715 4.445 90)
			(size 0.635 0.635)
			(layers "B.Cu" "B.Mask" "B.Paste")
			(net "GND")
		)
		(pad "49" smd circle
			(at -4.445 -4.445 90)
			(size 0.635 0.635)
			(layers "B.Cu" "B.Mask" "B.Paste")
			(net "NFP_PCIE0_PET2_N")
		)
		(pad "50" smd circle
			(at -4.445 -3.175 90)
			(size 0.635 0.635)
			(layers "B.Cu" "B.Mask" "B.Paste")
			(net "GND")
		)
		(pad "51" smd circle
			(at -4.445 -1.905 90)
			(size 0.635 0.635)
			(layers "B.Cu" "B.Mask" "B.Paste")
			(net "NFP_PCIE0_PER5_N")
		)
		(pad "52" smd circle
			(at -4.445 -0.635 90)
			(size 0.635 0.635)
			(layers "B.Cu" "B.Mask" "B.Paste")
			(net "GND")
		)
		(pad "53" smd circle
			(at -4.445 0.635 90)
			(size 0.635 0.635)
			(layers "B.Cu" "B.Mask" "B.Paste")
			(net "_NC_NCSI_RXD_1")
		)
		(pad "54" smd circle
			(at -4.445 1.905 90)
			(size 0.635 0.635)
			(layers "B.Cu" "B.Mask" "B.Paste")
			(net "GND")
		)
		(pad "55" smd circle
			(at -4.445 3.175 90)
			(size 0.635 0.635)
			(layers "B.Cu" "B.Mask" "B.Paste")
			(net "NFP_SERDES1_TX1_N")
		)
		(pad "56" smd circle
			(at -4.445 4.445 90)
			(size 0.635 0.635)
			(layers "B.Cu" "B.Mask" "B.Paste")
			(net "GND")
		)
		(pad "57" smd circle
			(at -3.175 -4.445 90)
			(size 0.635 0.635)
			(layers "B.Cu" "B.Mask" "B.Paste")
			(net "GND")
		)
		(pad "58" smd circle
			(at -3.175 -3.175 90)
			(size 0.635 0.635)
			(layers "B.Cu" "B.Mask" "B.Paste")
			(net "NFP_PCIE0_PET3_P")
		)
		(pad "59" smd circle
			(at -3.175 -1.905 90)
			(size 0.635 0.635)
			(layers "B.Cu" "B.Mask" "B.Paste")
			(net "GND")
		)
		(pad "60" smd circle
			(at -3.175 -0.635 90)
			(size 0.635 0.635)
			(layers "B.Cu" "B.Mask" "B.Paste")
			(net "NFP_PCIE0_PER4_P")
		)
		(pad "61" smd circle
			(at -3.175 0.635 90)
			(size 0.635 0.635)
			(layers "B.Cu" "B.Mask" "B.Paste")
			(net "GND")
		)
		(pad "62" smd circle
			(at -3.175 1.905 90)
			(size 0.635 0.635)
			(layers "B.Cu" "B.Mask" "B.Paste")
			(net "_NC_NCSI_TX_EN")
		)
		(pad "63" smd circle
			(at -3.175 3.175 90)
			(size 0.635 0.635)
			(layers "B.Cu" "B.Mask" "B.Paste")
			(net "GND")
		)
		(pad "64" smd circle
			(at -3.175 4.445 90)
			(size 0.635 0.635)
			(layers "B.Cu" "B.Mask" "B.Paste")
			(net "NFP_SERDES1_TX2_P")
		)
		(pad "65" smd circle
			(at -1.905 -4.445 90)
			(size 0.635 0.635)
			(layers "B.Cu" "B.Mask" "B.Paste")
			(net "GND")
		)
		(pad "66" smd circle
			(at -1.905 -3.175 90)
			(size 0.635 0.635)
			(layers "B.Cu" "B.Mask" "B.Paste")
			(net "NFP_PCIE0_PET3_N")
		)
		(pad "67" smd circle
			(at -1.905 -1.905 90)
			(size 0.635 0.635)
			(layers "B.Cu" "B.Mask" "B.Paste")
			(net "GND")
		)
		(pad "68" smd circle
			(at -1.905 -0.635 90)
			(size 0.635 0.635)
			(layers "B.Cu" "B.Mask" "B.Paste")
			(net "NFP_PCIE0_PER4_N")
		)
		(pad "69" smd circle
			(at -1.905 0.635 90)
			(size 0.635 0.635)
			(layers "B.Cu" "B.Mask" "B.Paste")
			(net "GND")
		)
		(pad "70" smd circle
			(at -1.905 1.905 90)
			(size 0.635 0.635)
			(layers "B.Cu" "B.Mask" "B.Paste")
			(net "_NC_NCSI_CLK_IN")
		)
		(pad "71" smd circle
			(at -1.905 3.175 90)
			(size 0.635 0.635)
			(layers "B.Cu" "B.Mask" "B.Paste")
			(net "GND")
		)
		(pad "72" smd circle
			(at -1.905 4.445 90)
			(size 0.635 0.635)
			(layers "B.Cu" "B.Mask" "B.Paste")
			(net "NFP_SERDES1_TX2_N")
		)
		(pad "73" smd circle
			(at -0.635 -4.445 90)
			(size 0.635 0.635)
			(layers "B.Cu" "B.Mask" "B.Paste")
			(net "NFP_PCIE0_PET4_P")
		)
		(pad "74" smd circle
			(at -0.635 -3.175 90)
			(size 0.635 0.635)
			(layers "B.Cu" "B.Mask" "B.Paste")
			(net "GND")
		)
		(pad "75" smd circle
			(at -0.635 -1.905 90)
			(size 0.635 0.635)
			(layers "B.Cu" "B.Mask" "B.Paste")
			(net "NFP_PCIE0_PER0_P")
		)
		(pad "76" smd circle
			(at -0.635 -0.635 90)
			(size 0.635 0.635)
			(layers "B.Cu" "B.Mask" "B.Paste")
			(net "GND")
		)
		(pad "77" smd circle
			(at -0.635 0.635 90)
			(size 0.635 0.635)
			(layers "B.Cu" "B.Mask" "B.Paste")
			(net "_NC_NCSI_CRS_DV")
		)
		(pad "78" smd circle
			(at -0.635 1.905 90)
			(size 0.635 0.635)
			(layers "B.Cu" "B.Mask" "B.Paste")
			(net "GND")
		)
		(pad "79" smd circle
			(at -0.635 3.175 90)
			(size 0.635 0.635)
			(layers "B.Cu" "B.Mask" "B.Paste")
			(net "NFP_SERDES1_TX3_P")
		)
		(pad "80" smd circle
			(at -0.635 4.445 90)
			(size 0.635 0.635)
			(layers "B.Cu" "B.Mask" "B.Paste")
			(net "GND")
		)
		(pad "81" smd circle
			(at 0.635 -4.445 90)
			(size 0.635 0.635)
			(layers "B.Cu" "B.Mask" "B.Paste")
			(net "NFP_PCIE0_PET4_N")
		)
		(pad "82" smd circle
			(at 0.635 -3.175 90)
			(size 0.635 0.635)
			(layers "B.Cu" "B.Mask" "B.Paste")
			(net "GND")
		)
		(pad "83" smd circle
			(at 0.635 -1.905 90)
			(size 0.635 0.635)
			(layers "B.Cu" "B.Mask" "B.Paste")
			(net "NFP_PCIE0_PER0_N")
		)
		(pad "84" smd circle
			(at 0.635 -0.635 90)
			(size 0.635 0.635)
			(layers "B.Cu" "B.Mask" "B.Paste")
			(net "GND")
		)
		(pad "85" smd circle
			(at 0.635 0.635 90)
			(size 0.635 0.635)
			(layers "B.Cu" "B.Mask" "B.Paste")
			(net "_NC_NCSI_RX_ER")
		)
		(pad "86" smd circle
			(at 0.635 1.905 90)
			(size 0.635 0.635)
			(layers "B.Cu" "B.Mask" "B.Paste")
			(net "GND")
		)
		(pad "87" smd circle
			(at 0.635 3.175 90)
			(size 0.635 0.635)
			(layers "B.Cu" "B.Mask" "B.Paste")
			(net "NFP_SERDES1_TX3_N")
		)
		(pad "88" smd circle
			(at 0.635 4.445 90)
			(size 0.635 0.635)
			(layers "B.Cu" "B.Mask" "B.Paste")
			(net "GND")
		)
		(pad "89" smd circle
			(at 1.905 -4.445 90)
			(size 0.635 0.635)
			(layers "B.Cu" "B.Mask" "B.Paste")
			(net "GND")
		)
		(pad "90" smd circle
			(at 1.905 -3.175 90)
			(size 0.635 0.635)
			(layers "B.Cu" "B.Mask" "B.Paste")
			(net "NFP_PCIE0_PET5_P")
		)
		(pad "91" smd circle
			(at 1.905 -1.905 90)
			(size 0.635 0.635)
			(layers "B.Cu" "B.Mask" "B.Paste")
			(net "GND")
		)
		(pad "92" smd circle
			(at 1.905 -0.635 90)
			(size 0.635 0.635)
			(layers "B.Cu" "B.Mask" "B.Paste")
			(net "NFP_PCIE0_PER1_P")
		)
		(pad "93" smd circle
			(at 1.905 0.635 90)
			(size 0.635 0.635)
			(layers "B.Cu" "B.Mask" "B.Paste")
			(net "GND")
		)
		(pad "94" smd circle
			(at 1.905 1.905 90)
			(size 0.635 0.635)
			(layers "B.Cu" "B.Mask" "B.Paste")
			(net "NWK0_LED_ACT_G_L")
		)
		(pad "95" smd circle
			(at 1.905 3.175 90)
			(size 0.635 0.635)
			(layers "B.Cu" "B.Mask" "B.Paste")
			(net "GND")
		)
		(pad "96" smd circle
			(at 1.905 4.445 90)
			(size 0.635 0.635)
			(layers "B.Cu" "B.Mask" "B.Paste")
			(net "NFP_SERDES1_RX0_P")
		)
		(pad "97" smd circle
			(at 3.175 -4.445 90)
			(size 0.635 0.635)
			(layers "B.Cu" "B.Mask" "B.Paste")
			(net "GND")
		)
		(pad "98" smd circle
			(at 3.175 -3.175 90)
			(size 0.635 0.635)
			(layers "B.Cu" "B.Mask" "B.Paste")
			(net "NFP_PCIE0_PET5_N")
		)
		(pad "99" smd circle
			(at 3.175 -1.905 90)
			(size 0.635 0.635)
			(layers "B.Cu" "B.Mask" "B.Paste")
			(net "GND")
		)
		(pad "100" smd circle
			(at 3.175 -0.635 90)
			(size 0.635 0.635)
			(layers "B.Cu" "B.Mask" "B.Paste")
			(net "NFP_PCIE0_PER1_N")
		)
		(pad "101" smd circle
			(at 3.175 0.635 90)
			(size 0.635 0.635)
			(layers "B.Cu" "B.Mask" "B.Paste")
			(net "GND")
		)
		(pad "102" smd circle
			(at 3.175 1.905 90)
			(size 0.635 0.635)
			(layers "B.Cu" "B.Mask" "B.Paste")
			(net "NWK0_LED_LINK_G_L")
		)
		(pad "103" smd circle
			(at 3.175 3.175 90)
			(size 0.635 0.635)
			(layers "B.Cu" "B.Mask" "B.Paste")
			(net "GND")
		)
		(pad "104" smd circle
			(at 3.175 4.445 90)
			(size 0.635 0.635)
			(layers "B.Cu" "B.Mask" "B.Paste")
			(net "NFP_SERDES1_RX0_N")
		)
		(pad "105" smd circle
			(at 4.445 -4.445 90)
			(size 0.635 0.635)
			(layers "B.Cu" "B.Mask" "B.Paste")
			(net "NFP_PCIE0_PET6_P")
		)
		(pad "106" smd circle
			(at 4.445 -3.175 90)
			(size 0.635 0.635)
			(layers "B.Cu" "B.Mask" "B.Paste")
			(net "GND")
		)
		(pad "107" smd circle
			(at 4.445 -1.905 90)
			(size 0.635 0.635)
			(layers "B.Cu" "B.Mask" "B.Paste")
			(net "NFP_PCIE0_PER2_P")
		)
		(pad "108" smd circle
			(at 4.445 -0.635 90)
			(size 0.635 0.635)
			(layers "B.Cu" "B.Mask" "B.Paste")
			(net "GND")
		)
		(pad "109" smd circle
			(at 4.445 0.635 90)
			(size 0.635 0.635)
			(layers "B.Cu" "B.Mask" "B.Paste")
			(net "NWK1_LED_ACT_G_L")
		)
		(pad "110" smd circle
			(at 4.445 1.905 90)
			(size 0.635 0.635)
			(layers "B.Cu" "B.Mask" "B.Paste")
			(net "GND")
		)
		(pad "111" smd circle
			(at 4.445 3.175 90)
			(size 0.635 0.635)
			(layers "B.Cu" "B.Mask" "B.Paste")
			(net "NFP_SERDES1_RX1_N")
		)
		(pad "112" smd circle
			(at 4.445 4.445 90)
			(size 0.635 0.635)
			(layers "B.Cu" "B.Mask" "B.Paste")
			(net "GND")
		)
		(pad "113" smd circle
			(at 5.715 -4.445 90)
			(size 0.635 0.635)
			(layers "B.Cu" "B.Mask" "B.Paste")
			(net "NFP_PCIE0_PET6_N")
		)
		(pad "114" smd circle
			(at 5.715 -3.175 90)
			(size 0.635 0.635)
			(layers "B.Cu" "B.Mask" "B.Paste")
			(net "GND")
		)
	)
)
